# T6G (Grand Teton) — schematic netlist excerpt (pin names and nets, part order shuffled) for the footprints in the layout excerpt that follows; sources: Cadence DE-HDL packaged netlist, KiCad conversion of 04192023_DAF0TMB3IC0_F0TG_MB_C_brd_V02_OCP.brd

C458  Q_CAP  0.1UF 10V 10% X7S  pkg C0201  page 356 : A = P0V9_CPU1_RT_2D ; B = GND
R1083  Q_RES  0 5% CHIP  pkg 0201LF  page 299 : A = NCF_CPU0_P2_GND ; B = GND
R435  Q_RES  0 5% CHIP  pkg 0402LF  page 28 : A = CLK_100M_REF_OUT_DP ; B = CLK_100M_REF_IN_DP

(kicad_pcb
	(version 20260206)
	(generator "pcbnew")
	(generator_version "10.0")
	(general
		(thickness 1.6)
		(legacy_teardrops no)
	)
	(paper "A4")
	(title_block
		(title "04192023_DAF0TMB3IC0_F0TG_MB_C_brd_V02_OCP.brd")
		(comment 1 "Grand Teton / footprints 5815-5817 of 8354")
	)
	(layers
		(0 "F.Cu" signal "TOP")
		(4 "In1.Cu" signal "GND")
		(6 "In2.Cu" signal "IN1")
		(8 "In3.Cu" signal "GND1")
		(10 "In4.Cu" signal "IN2")
		(12 "In5.Cu" signal "GND2")
		(14 "In6.Cu" signal "IN3")
		(16 "In7.Cu" signal "GND3")
		(18 "In8.Cu" signal "VCC")
		(20 "In9.Cu" signal "VCC1")
		(22 "In10.Cu" signal "GND4")
		(24 "In11.Cu" signal "IN4")
		(26 "In12.Cu" signal "GND5")
		(28 "In13.Cu" signal "IN5")
		(30 "In14.Cu" signal "GND6")
		(32 "In15.Cu" signal "IN6")
		(34 "In16.Cu" signal "GND7")
		(2 "B.Cu" signal "BOTTOM")
		(9 "F.Adhes" user "F.Adhesive")
		(11 "B.Adhes" user "B.Adhesive")
		(13 "F.Paste" user "Package Geometry/Pastemask Top")
		(15 "B.Paste" user "Package Geometry/Pastemask Bottom")
		(5 "F.SilkS" user "Ref Des/Silkscreen Top")
		(7 "B.SilkS" user "Ref Des/Silkscreen Bottom")
		(1 "F.Mask" user "Board Geometry/Soldermask Top")
		(3 "B.Mask" user "Board Geometry/Soldermask Bottom")
		(17 "Dwgs.User" user "User.Drawings")
		(19 "Cmts.User" user "User.Comments")
		(21 "Eco1.User" user "User.Eco1")
		(23 "Eco2.User" user "User.Eco2")
		(25 "Edge.Cuts" user "Board Geometry/Outline")
		(27 "Margin" user)
		(31 "F.CrtYd" user "Package Geometry/Place Bound Top")
		(29 "B.CrtYd" user "Package Geometry/Place Bound Bottom")
		(35 "F.Fab" user "Ref Des/Assembly Top")
		(33 "B.Fab" user "Ref Des/Assembly Bottom")
	)
	(footprint ""
		(layer "B.Cu")
		(at 424.783758 -391.686288 180)
		(property "Reference" "R1083"
			(at 0 0 0)
			(layer "B.SilkS")
			(hide yes)
			(effects
				(font
					(size 1.27 1.27)
				)
				(justify mirror)
			)
		)
		(property "Value" ""
			(at 0 0 0)
			(layer "B.Fab")
			(effects
				(font
					(size 1.27 1.27)
				)
				(justify mirror)
			)
		)
		(duplicate_pad_numbers_are_jumpers no)
		(fp_line
			(start 0.32512 0.175006)
			(end 0.32512 -0.175006)
			(stroke
				(width 0.1)
				(type default)
			)
			(layer "B.Fab")
		)
		(fp_line
			(start 0.32512 -0.175006)
			(end -0.32512 -0.175006)
			(stroke
				(width 0.1)
				(type default)
			)
			(layer "B.Fab")
		)
		(fp_line
			(start -0.32512 0.175006)
			(end 0.32512 0.175006)
			(stroke
				(width 0.1)
				(type default)
			)
			(layer "B.Fab")
		)
		(fp_line
			(start -0.32512 -0.175006)
			(end -0.32512 0.175006)
			(stroke
				(width 0.1)
				(type default)
			)
			(layer "B.Fab")
		)
		(pad "1" smd rect
			(at 0.2667 0)
			(size 0.3048 0.381)
			(layers "B.Cu" "B.Mask" "B.Paste")
			(net "NCF_CPU0_P2_GND")
		)
		(pad "2" smd rect
			(at -0.2667 0 180)
			(size 0.3048 0.381)
			(layers "B.Cu" "B.Mask" "B.Paste")
			(net "GND")
		)
	)
	(footprint ""
		(layer "B.Cu")
		(at 339.566758 -214.880952 90)
		(property "Reference" "R435"
			(at 0 0 90)
			(layer "B.SilkS")
			(hide yes)
			(effects
				(font
					(size 1.27 1.27)
				)
				(justify mirror)
			)
		)
		(property "Value" ""
			(at 0 0 90)
			(layer "B.Fab")
			(effects
				(font
					(size 1.27 1.27)
				)
				(justify mirror)
			)
		)
		(duplicate_pad_numbers_are_jumpers no)
		(fp_line
			(start 0.384048 -0.4064)
			(end -0.377952 -0.4064)
			(stroke
				(width 0.1524)
				(type default)
			)
			(layer "B.SilkS")
		)
		(fp_line
			(start -0.7874 0.132842)
			(end -0.7874 0.4064)
			(stroke
				(width 0.1524)
				(type default)
			)
			(layer "B.SilkS")
		)
		(fp_line
			(start 0.7874 0.4064)
			(end 0.7874 0.005842)
			(stroke
				(width 0.1524)
				(type default)
			)
			(layer "B.SilkS")
		)
		(fp_line
			(start -0.7874 0.4064)
			(end 0.7874 0.4064)
			(stroke
				(width 0.1524)
				(type default)
			)
			(layer "B.SilkS")
		)
		(fp_line
			(start 0.67945 -0.305054)
			(end 0.12065 -0.305054)
			(stroke
				(width 0.1)
				(type default)
			)
			(layer "B.Fab")
		)
		(fp_line
			(start 0.12065 -0.305054)
			(end 0.12065 -0.2794)
			(stroke
				(width 0.1)
				(type default)
			)
			(layer "B.Fab")
		)
		(fp_line
			(start -0.12065 -0.3048)
			(end -0.67945 -0.3048)
			(stroke
				(width 0.1)
				(type default)
			)
			(layer "B.Fab")
		)
		(fp_line
			(start -0.67945 -0.3048)
			(end -0.67945 0.3048)
			(stroke
				(width 0.1)
				(type default)
			)
			(layer "B.Fab")
		)
		(fp_line
			(start 0.12065 -0.2794)
			(end -0.12065 -0.2794)
			(stroke
				(width 0.1)
				(type default)
			)
			(layer "B.Fab")
		)
		(fp_line
			(start -0.12065 -0.2794)
			(end -0.12065 -0.3048)
			(stroke
				(width 0.1)
				(type default)
			)
			(layer "B.Fab")
		)
		(fp_line
			(start 0.12065 0.2794)
			(end 0.12065 0.3048)
			(stroke
				(width 0.1)
				(type default)
			)
			(layer "B.Fab")
		)
		(fp_line
			(start -0.120396 0.2794)
			(end 0.12065 0.2794)
			(stroke
				(width 0.1)
				(type default)
			)
			(layer "B.Fab")
		)
		(fp_line
			(start 0.67945 0.3048)
			(end 0.67945 -0.305054)
			(stroke
				(width 0.1)
				(type default)
			)
			(layer "B.Fab")
		)
		(fp_line
			(start 0.12065 0.3048)
			(end 0.67945 0.3048)
			(stroke
				(width 0.1)
				(type default)
			)
			(layer "B.Fab")
		)
		(fp_line
			(start -0.120396 0.3048)
			(end -0.120396 0.2794)
			(stroke
				(width 0.1)
				(type default)
			)
			(layer "B.Fab")
		)
		(fp_line
			(start -0.67945 0.3048)
			(end -0.120396 0.3048)
			(stroke
				(width 0.1)
				(type default)
			)
			(layer "B.Fab")
		)
		(pad "1" smd circle
			(at 0.40005 0 270)
			(size 0 0)
			(layers "B.Cu" "B.Mask" "B.Paste")
			(net "CLK_100M_REF_OUT_DP")
		)
		(pad "2" smd circle
			(at -0.40005 0 270)
			(size 0 0)
			(layers "B.Cu" "B.Mask" "B.Paste")
			(net "CLK_100M_REF_IN_DP")
		)
	)
	(footprint ""
		(layer "B.Cu")
		(at 126.618492 -388.011162 -90)
		(property "Reference" "C458"
			(at 0 0 90)
			(layer "B.SilkS")
			(hide yes)
			(effects
				(font
					(size 1.27 1.27)
				)
				(justify mirror)
			)
		)
		(property "Value" ""
			(at 0 0 90)
			(layer "B.Fab")
			(effects
				(font
					(size 1.27 1.27)
				)
				(justify mirror)
			)
		)
		(duplicate_pad_numbers_are_jumpers no)
		(fp_line
			(start -0.299974 0.150114)
			(end 0.299974 0.150114)
			(stroke
				(width 0.1)
				(type default)
			)
			(layer "B.Fab")
		)
		(fp_line
			(start 0.299974 0.150114)
			(end 0.299974 -0.150114)
			(stroke
				(width 0.1)
				(type default)
			)
			(layer "B.Fab")
		)
		(fp_line
			(start -0.299974 -0.150114)
			(end -0.299974 0.150114)
			(stroke
				(width 0.1)
				(type default)
			)
			(layer "B.Fab")
		)
		(fp_line
			(start 0.299974 -0.150114)
			(end -0.299974 -0.150114)
			(stroke
				(width 0.1)
				(type default)
			)
			(layer "B.Fab")
		)
		(pad "1" smd rect
			(at 0.2667 0 90)
			(size 0.3048 0.381)
			(layers "B.Cu" "B.Mask" "B.Paste")
			(net "P0V9_CPU1_RT_2D")
		)
		(pad "2" smd rect
			(at -0.2667 0 90)
			(size 0.3048 0.381)
			(layers "B.Cu" "B.Mask" "B.Paste")
			(net "GND")
		)
	)
)
